(kicad_pcb
	(version 20260206)
	(generator "pcbnew")
	(generator_version "10.0")
	(general
		(thickness 1.6)
		(legacy_teardrops no)
	)
	(paper "A4")
	(title_block
		(title "timecard-production-celestica-r4006 — R4006-B0001-02_R01.brd")
		(comment 1 "Time Appliance Project (Time Card) / footprints 644-648 of 1113")
	)
	(layers
		(0 "F.Cu" signal "TOP")
		(4 "In1.Cu" signal "L02_GND1")
		(6 "In2.Cu" signal "L03_SIG1")
		(8 "In3.Cu" signal "L04_GND2")
		(10 "In4.Cu" signal "L05_VCC1")
		(12 "In5.Cu" signal "L06_VCC2")
		(14 "In6.Cu" signal "L07_GND3")
		(16 "In7.Cu" signal "L08_SIG2")
		(18 "In8.Cu" signal "L09_GND4")
		(2 "B.Cu" signal "BOTTOM")
		(9 "F.Adhes" user "F.Adhesive")
		(11 "B.Adhes" user "B.Adhesive")
		(13 "F.Paste" user "Package Geometry/Pastemask Top")
		(15 "B.Paste" user "Package Geometry/Pastemask Bottom")
		(5 "F.SilkS" user "Ref Des/Silkscreen Top")
		(7 "B.SilkS" user "Ref Des/Silkscreen Bottom")
		(1 "F.Mask" user "Board Geometry/Soldermask Top")
		(3 "B.Mask" user "Board Geometry/Soldermask Bottom")
		(17 "Dwgs.User" user "User.Drawings")
		(19 "Cmts.User" user "User.Comments")
		(21 "Eco1.User" user "User.Eco1")
		(23 "Eco2.User" user "User.Eco2")
		(25 "Edge.Cuts" user "Board Geometry/Outline")
		(27 "Margin" user)
		(31 "F.CrtYd" user "Package Geometry/Place Bound Top")
		(29 "B.CrtYd" user "Package Geometry/Place Bound Bottom")
		(35 "F.Fab" user "Ref Des/Assembly Top")
		(33 "B.Fab" user "Ref Des/Assembly Bottom")
	)
	(footprint ""
		(layer "F.Cu")
		(at 54.0512 -74.9808 90)
		(property "Reference" "R412"
			(at -0.5588 4.40817 90)
			(unlocked yes)
			(layer "F.SilkS")
			(effects
				(font
					(size 0.7874 0.5842)
					(thickness 0.1524)
				)
			)
		)
		(property "Value" "VAL*"
			(at 0.02032 2.13233 90)
			(unlocked yes)
			(layer "F.Fab")
			(hide yes)
			(effects
				(font
					(size 0.7874 0.5842)
					(thickness 0.1524)
				)
			)
		)
		(property "Device Type" "RESISTOR-G155-14701-01,4.7KOHMA"
			(at 0.008382 1.210564 90)
			(unlocked yes)
			(layer "F.Fab")
			(hide yes)
			(effects
				(font
					(size 0.7874 0.5842)
					(thickness 0.1524)
				)
			)
		)
		(property "User Part Number" "PARTNUM*"
			(at 0.02032 4.024884 90)
			(unlocked yes)
			(layer "Cmts.User")
			(hide yes)
			(effects
				(font
					(size 0.7874 0.5842)
					(thickness 0.1524)
				)
			)
		)
		(property "Tolerance" "TOL*"
			(at 0.044704 3.05435 90)
			(unlocked yes)
			(layer "Cmts.User")
			(hide yes)
			(effects
				(font
					(size 0.7874 0.5842)
					(thickness 0.1524)
				)
			)
		)
		(duplicate_pad_numbers_are_jumpers no)
		(fp_line
			(start 1.143 -0.5588)
			(end -1.143 -0.5588)
			(stroke
				(width 0.1)
				(type default)
			)
			(layer "F.SilkS")
		)
		(fp_line
			(start -1.143 -0.5588)
			(end -1.143 0.5588)
			(stroke
				(width 0.1)
				(type default)
			)
			(layer "F.SilkS")
		)
		(fp_line
			(start 1.143 0.5588)
			(end 1.143 -0.5588)
			(stroke
				(width 0.1)
				(type default)
			)
			(layer "F.SilkS")
		)
		(fp_line
			(start -1.143 0.5588)
			(end 1.143 0.5588)
			(stroke
				(width 0.1)
				(type default)
			)
			(layer "F.SilkS")
		)
		(fp_rect
			(start -1.143 0.5588)
			(end 1.143 -0.5588)
			(stroke
				(width 0)
				(type default)
			)
			(fill no)
			(layer "F.CrtYd")
		)
		(fp_line
			(start 0.508 -0.3048)
			(end -0.508 -0.3048)
			(stroke
				(width 0.1)
				(type default)
			)
			(layer "F.Fab")
		)
		(fp_line
			(start -0.508 -0.3048)
			(end -0.508 0.3048)
			(stroke
				(width 0.1)
				(type default)
			)
			(layer "F.Fab")
		)
		(fp_line
			(start 0.508 0.3048)
			(end 0.508 -0.3048)
			(stroke
				(width 0.1)
				(type default)
			)
			(layer "F.Fab")
		)
		(fp_line
			(start -0.508 0.3048)
			(end 0.508 0.3048)
			(stroke
				(width 0.1)
				(type default)
			)
			(layer "F.Fab")
		)
		(pad "1" smd rect
			(at -0.5334 0 90)
			(size 0.7112 0.6096)
			(layers "F.Cu" "F.Mask" "F.Paste")
			(net "XP3R3V_FPGA")
		)
		(pad "2" smd rect
			(at 0.5334 0 90)
			(size 0.7112 0.6096)
			(layers "F.Cu" "F.Mask" "F.Paste")
			(net "UNNAMED_6_LM75BDPTSSOP8_I59_A1")
		)
		(zone
			(layer "F.Cu")
			(hatch none 0.5)
			(connect_pads
				(clearance 0)
			)
			(min_thickness 0.25)
			(keepout
				(tracks not_allowed)
				(vias allowed)
				(pads allowed)
				(copperpour not_allowed)
				(footprints allowed)
			)
			(placement
				(enabled no)
				(sheetname "")
			)
			(fill
				(thermal_gap 0.5)
				(thermal_bridge_width 0.5)
				(island_removal_mode 0)
			)
			(polygon
				(pts
					(xy 54.356 -74.9046) (xy 54.356 -75.057) (xy 53.7464 -75.057) (xy 53.7464 -74.9046)
				)
			)
		)
		(zone
			(layer "F.Cu")
			(hatch none 0.5)
			(connect_pads
				(clearance 0)
			)
			(min_thickness 0.25)
			(keepout
				(tracks allowed)
				(vias not_allowed)
				(pads allowed)
				(copperpour not_allowed)
				(footprints allowed)
			)
			(placement
				(enabled no)
				(sheetname "")
			)
			(fill
				(thermal_gap 0.5)
				(thermal_bridge_width 0.5)
				(island_removal_mode 0)
			)
			(polygon
				(pts
					(xy 54.356 -74.9046) (xy 54.356 -75.057) (xy 53.7464 -75.057) (xy 53.7464 -74.9046)
				)
			)
		)
	)
	(footprint ""
		(layer "F.Cu")
		(at 138.811 -59.563 -90)
		(property "Reference" "R245"
			(at -3.048 1.48463 90)
			(unlocked yes)
			(layer "F.SilkS")
			(effects
				(font
					(size 0.7874 0.5842)
					(thickness 0.1524)
				)
			)
		)
		(property "Value" "VAL*"
			(at 0.02032 2.13233 270)
			(unlocked yes)
			(layer "F.Fab")
			(hide yes)
			(effects
				(font
					(size 0.7874 0.5842)
					(thickness 0.1524)
				)
			)
		)
		(property "Device Type" "RESISTOR-G155-100R0-J0,0OHM,-"
			(at 0.008382 1.210564 270)
			(unlocked yes)
			(layer "F.Fab")
			(hide yes)
			(effects
				(font
					(size 0.7874 0.5842)
					(thickness 0.1524)
				)
			)
		)
		(property "User Part Number" "PARTNUM*"
			(at 0.02032 4.024884 270)
			(unlocked yes)
			(layer "Cmts.User")
			(hide yes)
			(effects
				(font
					(size 0.7874 0.5842)
					(thickness 0.1524)
				)
			)
		)
		(property "Tolerance" "TOL*"
			(at 0.044704 3.05435 270)
			(unlocked yes)
			(layer "Cmts.User")
			(hide yes)
			(effects
				(font
					(size 0.7874 0.5842)
					(thickness 0.1524)
				)
			)
		)
		(duplicate_pad_numbers_are_jumpers no)
		(fp_line
			(start -1.143 0.5588)
			(end 1.143 0.5588)
			(stroke
				(width 0.1)
				(type default)
			)
			(layer "F.SilkS")
		)
		(fp_line
			(start 1.143 0.5588)
			(end 1.143 -0.5588)
			(stroke
				(width 0.1)
				(type default)
			)
			(layer "F.SilkS")
		)
		(fp_line
			(start -1.143 -0.5588)
			(end -1.143 0.5588)
			(stroke
				(width 0.1)
				(type default)
			)
			(layer "F.SilkS")
		)
		(fp_line
			(start 1.143 -0.5588)
			(end -1.143 -0.5588)
			(stroke
				(width 0.1)
				(type default)
			)
			(layer "F.SilkS")
		)
		(fp_rect
			(start 1.143 0.5588)
			(end -1.143 -0.5588)
			(stroke
				(width 0)
				(type default)
			)
			(fill no)
			(layer "F.CrtYd")
		)
		(fp_line
			(start -0.508 0.3048)
			(end 0.508 0.3048)
			(stroke
				(width 0.1)
				(type default)
			)
			(layer "F.Fab")
		)
		(fp_line
			(start 0.508 0.3048)
			(end 0.508 -0.3048)
			(stroke
				(width 0.1)
				(type default)
			)
			(layer "F.Fab")
		)
		(fp_line
			(start -0.508 -0.3048)
			(end -0.508 0.3048)
			(stroke
				(width 0.1)
				(type default)
			)
			(layer "F.Fab")
		)
		(fp_line
			(start 0.508 -0.3048)
			(end -0.508 -0.3048)
			(stroke
				(width 0.1)
				(type default)
			)
			(layer "F.Fab")
		)
		(pad "1" smd rect
			(at -0.5334 0 270)
			(size 0.7112 0.6096)
			(layers "F.Cu" "F.Mask" "F.Paste")
			(net "XP1R0V_FPGA_PG")
		)
		(pad "2" smd rect
			(at 0.5334 0 270)
			(size 0.7112 0.6096)
			(layers "F.Cu" "F.Mask" "F.Paste")
			(net "XP1R0V_PG")
		)
		(zone
			(layer "F.Cu")
			(hatch none 0.5)
			(connect_pads
				(clearance 0)
			)
			(min_thickness 0.25)
			(keepout
				(tracks allowed)
				(vias not_allowed)
				(pads allowed)
				(copperpour not_allowed)
				(footprints allowed)
			)
			(placement
				(enabled no)
				(sheetname "")
			)
			(fill
				(thermal_gap 0.5)
				(thermal_bridge_width 0.5)
				(island_removal_mode 0)
			)
			(polygon
				(pts
					(xy 138.5062 -59.4868) (xy 139.1158 -59.4868) (xy 139.1158 -59.6392) (xy 138.5062 -59.6392)
				)
			)
		)
	)
	(footprint ""
		(layer "F.Cu")
		(at 133.858 -23.368)
		(property "Reference" "C92"
			(at -0.635 -4.78663 0)
			(unlocked yes)
			(layer "F.SilkS")
			(effects
				(font
					(size 0.7874 0.5842)
					(thickness 0.1524)
				)
			)
		)
		(property "Value" "VAL*"
			(at 0.0762 2.067306 0)
			(unlocked yes)
			(layer "F.Fab")
			(hide yes)
			(effects
				(font
					(size 0.7874 0.5842)
					(thickness 0.1524)
				)
			)
		)
		(property "Device Type" "CAPACITOR-G105-0B104-EK,0.1UF,A"
			(at 0.0508 1.127506 0)
			(unlocked yes)
			(layer "F.Fab")
			(hide yes)
			(effects
				(font
					(size 0.7874 0.5842)
					(thickness 0.1524)
				)
			)
		)
		(property "User Part Number" "PARTNUM*"
			(at 0.1016 4.023106 0)
			(unlocked yes)
			(layer "Cmts.User")
			(hide yes)
			(effects
				(font
					(size 0.7874 0.5842)
					(thickness 0.1524)
				)
			)
		)
		(property "Tolerance" "TOL*"
			(at 0.0762 3.032506 0)
			(unlocked yes)
			(layer "Cmts.User")
			(hide yes)
			(effects
				(font
					(size 0.7874 0.5842)
					(thickness 0.1524)
				)
			)
		)
		(duplicate_pad_numbers_are_jumpers no)
		(fp_line
			(start -1.143 -0.5588)
			(end -1.143 0.5588)
			(stroke
				(width 0.1)
				(type default)
			)
			(layer "F.SilkS")
		)
		(fp_line
			(start -1.143 0.5588)
			(end 1.143 0.5588)
			(stroke
				(width 0.1)
				(type default)
			)
			(layer "F.SilkS")
		)
		(fp_line
			(start 1.143 -0.5588)
			(end -1.143 -0.5588)
			(stroke
				(width 0.1)
				(type default)
			)
			(layer "F.SilkS")
		)
		(fp_line
			(start 1.143 0.5588)
			(end 1.143 -0.5588)
			(stroke
				(width 0.1)
				(type default)
			)
			(layer "F.SilkS")
		)
		(fp_rect
			(start 1.143 -0.5588)
			(end -1.143 0.5588)
			(stroke
				(width 0)
				(type default)
			)
			(fill no)
			(layer "F.CrtYd")
		)
		(fp_line
			(start -0.508 -0.3048)
			(end -0.508 0.3048)
			(stroke
				(width 0.1)
				(type default)
			)
			(layer "F.Fab")
		)
		(fp_line
			(start -0.508 0.3048)
			(end 0.508 0.3048)
			(stroke
				(width 0.1)
				(type default)
			)
			(layer "F.Fab")
		)
		(fp_line
			(start 0.508 -0.3048)
			(end -0.508 -0.3048)
			(stroke
				(width 0.1)
				(type default)
			)
			(layer "F.Fab")
		)
		(fp_line
			(start 0.508 0.3048)
			(end 0.508 -0.3048)
			(stroke
				(width 0.1)
				(type default)
			)
			(layer "F.Fab")
		)
		(pad "1" smd rect
			(at -0.5334 0)
			(size 0.7112 0.6096)
			(layers "F.Cu" "F.Mask" "F.Paste")
			(net "XP3R3V_FPGA")
		)
		(pad "2" smd rect
			(at 0.5334 0)
			(size 0.7112 0.6096)
			(layers "F.Cu" "F.Mask" "F.Paste")
			(net "SG")
		)
		(zone
			(layer "F.Cu")
			(hatch none 0.5)
			(connect_pads
				(clearance 0)
			)
			(min_thickness 0.25)
			(keepout
				(tracks allowed)
				(vias not_allowed)
				(pads allowed)
				(copperpour not_allowed)
				(footprints allowed)
			)
			(placement
				(enabled no)
				(sheetname "")
			)
			(fill
				(thermal_gap 0.5)
				(thermal_bridge_width 0.5)
				(island_removal_mode 0)
			)
			(polygon
				(pts
					(xy 133.9342 -23.6728) (xy 133.7818 -23.6728) (xy 133.7818 -23.0632) (xy 133.9342 -23.0632)
				)
			)
		)
	)
	(footprint ""
		(layer "F.Cu")
		(at 27.305 -75.184 -90)
		(property "Reference" "R353"
			(at 3.175 -0.29337 90)
			(unlocked yes)
			(layer "F.SilkS")
			(effects
				(font
					(size 0.7874 0.5842)
					(thickness 0.1524)
				)
			)
		)
		(property "Value" "VAL*"
			(at 0.02032 2.13233 270)
			(unlocked yes)
			(layer "F.Fab")
			(hide yes)
			(effects
				(font
					(size 0.7874 0.5842)
					(thickness 0.1524)
				)
			)
		)
		(property "Tolerance" "TOL*"
			(at 0.044704 3.05435 270)
			(unlocked yes)
			(layer "Cmts.User")
			(hide yes)
			(effects
				(font
					(size 0.7874 0.5842)
					(thickness 0.1524)
				)
			)
		)
		(property "User Part Number" "PARTNUM*"
			(at 0.02032 4.024884 270)
			(unlocked yes)
			(layer "Cmts.User")
			(hide yes)
			(effects
				(font
					(size 0.7874 0.5842)
					(thickness 0.1524)
				)
			)
		)
		(property "Device Type" "RESISTOR-G155-11000-01,100OHM,A"
			(at 0.008382 1.210564 270)
			(unlocked yes)
			(layer "F.Fab")
			(hide yes)
			(effects
				(font
					(size 0.7874 0.5842)
					(thickness 0.1524)
				)
			)
		)
		(duplicate_pad_numbers_are_jumpers no)
		(fp_line
			(start -1.143 0.5588)
			(end 1.143 0.5588)
			(stroke
				(width 0.1)
				(type default)
			)
			(layer "F.SilkS")
		)
		(fp_line
			(start 1.143 0.5588)
			(end 1.143 -0.5588)
			(stroke
				(width 0.1)
				(type default)
			)
			(layer "F.SilkS")
		)
		(fp_line
			(start -1.143 -0.5588)
			(end -1.143 0.5588)
			(stroke
				(width 0.1)
				(type default)
			)
			(layer "F.SilkS")
		)
		(fp_line
			(start 1.143 -0.5588)
			(end -1.143 -0.5588)
			(stroke
				(width 0.1)
				(type default)
			)
			(layer "F.SilkS")
		)
		(fp_poly
			(pts
				(xy -1.143 0.5588) (xy 1.143 0.5588) (xy 1.143 -0.5588) (xy -1.143 -0.5588)
			)
			(stroke
				(width 0)
				(type default)
			)
			(fill no)
			(layer "F.CrtYd")
		)
		(fp_line
			(start -0.508 0.3048)
			(end 0.508 0.3048)
			(stroke
				(width 0.1)
				(type default)
			)
			(layer "F.Fab")
		)
		(fp_line
			(start 0.508 0.3048)
			(end 0.508 -0.3048)
			(stroke
				(width 0.1)
				(type default)
			)
			(layer "F.Fab")
		)
		(fp_line
			(start -0.508 -0.3048)
			(end -0.508 0.3048)
			(stroke
				(width 0.1)
				(type default)
			)
			(layer "F.Fab")
		)
		(fp_line
			(start 0.508 -0.3048)
			(end -0.508 -0.3048)
			(stroke
				(width 0.1)
				(type default)
			)
			(layer "F.Fab")
		)
		(pad "1" smd rect
			(at -0.5334 0 270)
			(size 0.7112 0.6096)
			(layers "F.Cu" "F.Mask" "F.Paste")
			(net "R_FT4232_CHC_TX")
		)
		(pad "2" smd rect
			(at 0.5334 0 270)
			(size 0.7112 0.6096)
			(layers "F.Cu" "F.Mask" "F.Paste")
			(net "UART_FT4232_TX_FPGA_RX")
		)
		(zone
			(layer "F.Cu")
			(hatch none 0.5)
			(connect_pads
				(clearance 0)
			)
			(min_thickness 0.25)
			(keepout
				(tracks not_allowed)
				(vias allowed)
				(pads allowed)
				(copperpour not_allowed)
				(footprints allowed)
			)
			(placement
				(enabled no)
				(sheetname "")
			)
			(fill
				(thermal_gap 0.5)
				(thermal_bridge_width 0.5)
				(island_removal_mode 0)
			)
			(polygon
				(pts
					(xy 27.0002 -75.2602) (xy 27.0002 -75.1078) (xy 27.6098 -75.1078) (xy 27.6098 -75.2602)
				)
			)
		)
		(zone
			(layer "F.Cu")
			(hatch none 0.5)
			(connect_pads
				(clearance 0)
			)
			(min_thickness 0.25)
			(keepout
				(tracks allowed)
				(vias not_allowed)
				(pads allowed)
				(copperpour not_allowed)
				(footprints allowed)
			)
			(placement
				(enabled no)
				(sheetname "")
			)
			(fill
				(thermal_gap 0.5)
				(thermal_bridge_width 0.5)
				(island_removal_mode 0)
			)
			(polygon
				(pts
					(xy 27.0002 -75.2602) (xy 27.0002 -75.1078) (xy 27.6098 -75.1078) (xy 27.6098 -75.2602)
				)
			)
		)
	)
	(footprint ""
		(layer "F.Cu")
		(at 37.084 -77.216 -90)
		(property "Reference" "C308"
			(at 1.27 3.00863 90)
			(unlocked yes)
			(layer "F.SilkS")
			(effects
				(font
					(size 0.7874 0.5842)
					(thickness 0.1524)
				)
			)
		)
		(property "Value" "VAL*"
			(at 0.0762 3.134106 270)
			(unlocked yes)
			(layer "F.Fab")
			(hide yes)
			(effects
				(font
					(size 0.7874 0.5842)
					(thickness 0.1524)
				)
			)
		)
		(property "Tolerance" "TOL*"
			(at 0.0762 4.048506 270)
			(unlocked yes)
			(layer "Cmts.User")
			(hide yes)
			(effects
				(font
					(size 0.7874 0.5842)
					(thickness 0.1524)
				)
			)
		)
		(property "User Part Number" "PARTNUM*"
			(at 0.1016 5.013706 270)
			(unlocked yes)
			(layer "Cmts.User")
			(hide yes)
			(effects
				(font
					(size 0.7874 0.5842)
					(thickness 0.1524)
				)
			)
		)
		(property "Device Type" "CAPACITOR-G107-0F106-EM,10UF,2A"
			(at 0.0508 2.194306 270)
			(unlocked yes)
			(layer "F.Fab")
			(hide yes)
			(effects
				(font
					(size 0.7874 0.5842)
					(thickness 0.1524)
				)
			)
		)
		(duplicate_pad_numbers_are_jumpers no)
		(fp_line
			(start -1.5748 0.9398)
			(end 1.5748 0.9398)
			(stroke
				(width 0.1)
				(type default)
			)
			(layer "F.SilkS")
		)
		(fp_line
			(start 1.5748 0.9398)
			(end 1.5748 -0.9398)
			(stroke
				(width 0.1)
				(type default)
			)
			(layer "F.SilkS")
		)
		(fp_line
			(start -1.5748 -0.9398)
			(end -1.5748 0.9398)
			(stroke
				(width 0.1)
				(type default)
			)
			(layer "F.SilkS")
		)
		(fp_line
			(start 1.5748 -0.9398)
			(end -1.5748 -0.9398)
			(stroke
				(width 0.1)
				(type default)
			)
			(layer "F.SilkS")
		)
		(fp_poly
			(pts
				(xy -1.5748 0.9398) (xy 1.5748 0.9398) (xy 1.5748 -0.9398) (xy -1.5748 -0.9398)
			)
			(stroke
				(width 0)
				(type default)
			)
			(fill no)
			(layer "F.CrtYd")
		)
		(fp_line
			(start -1.016 0.635)
			(end 1.016 0.635)
			(stroke
				(width 0.1)
				(type default)
			)
			(layer "F.Fab")
		)
		(fp_line
			(start 1.016 0.635)
			(end 1.016 -0.635)
			(stroke
				(width 0.1)
				(type default)
			)
			(layer "F.Fab")
		)
		(fp_line
			(start -1.016 -0.635)
			(end -1.016 0.635)
			(stroke
				(width 0.1)
				(type default)
			)
			(layer "F.Fab")
		)
		(fp_line
			(start 1.016 -0.635)
			(end -1.016 -0.635)
			(stroke
				(width 0.1)
				(type default)
			)
			(layer "F.Fab")
		)
		(pad "1" smd rect
			(at -0.8382 0 270)
			(size 0.9652 1.3716)
			(layers "F.Cu" "F.Mask" "F.Paste")
			(net "XP3R3V_FT4232")
		)
		(pad "2" smd rect
			(at 0.8382 0 270)
			(size 0.9652 1.3716)
			(layers "F.Cu" "F.Mask" "F.Paste")
			(net "SG")
		)
		(zone
			(layer "F.Cu")
			(hatch none 0.5)
			(connect_pads
				(clearance 0)
			)
			(min_thickness 0.25)
			(keepout
				(tracks allowed)
				(vias not_allowed)
				(pads allowed)
				(copperpour not_allowed)
				(footprints allowed)
			)
			(placement
				(enabled no)
				(sheetname "")
			)
			(fill
				(thermal_gap 0.5)
				(thermal_bridge_width 0.5)
				(island_removal_mode 0)
			)
			(polygon
				(pts
					(xy 36.449 -77.4446) (xy 36.449 -76.9874) (xy 37.719 -76.9874) (xy 37.719 -77.4446)
				)
			)
		)
		(zone
			(layer "F.Cu")
			(hatch none 0.5)
			(connect_pads
				(clearance 0)
			)
			(min_thickness 0.25)
			(keepout
				(tracks not_allowed)
				(vias allowed)
				(pads allowed)
				(copperpour not_allowed)
				(footprints allowed)
			)
			(placement
				(enabled no)
				(sheetname "")
			)
			(fill
				(thermal_gap 0.5)
				(thermal_bridge_width 0.5)
				(island_removal_mode 0)
			)
			(polygon
				(pts
					(xy 36.449 -77.4446) (xy 36.449 -76.9874) (xy 37.719 -76.9874) (xy 37.719 -77.4446)
				)
			)
		)
	)
)
